(kicad_pcb
	(version 20260206)
	(generator "pcbnew")
	(generator_version "10.0")
	(general
		(thickness 1.6)
		(legacy_teardrops no)
	)
	(paper "A4")
	(title_block
		(title "v1-chassis-manager — T6M_CM_d_v01_1031_1645.brd")
		(comment 1 "Open CloudServer (Microsoft) / footprints 436-440 of 2512")
	)
	(layers
		(0 "F.Cu" signal "TOP")
		(4 "In1.Cu" signal "GND1")
		(6 "In2.Cu" signal "IN1")
		(8 "In3.Cu" signal "VCC1")
		(10 "In4.Cu" signal "VCC2")
		(12 "In5.Cu" signal "GND2")
		(14 "In6.Cu" signal "IN2")
		(16 "In7.Cu" signal "IN3")
		(18 "In8.Cu" signal "GND3")
		(2 "B.Cu" signal "BOTTOM")
		(9 "F.Adhes" user "F.Adhesive")
		(11 "B.Adhes" user "B.Adhesive")
		(13 "F.Paste" user "Package Geometry/Pastemask Top")
		(15 "B.Paste" user "Package Geometry/Pastemask Bottom")
		(5 "F.SilkS" user "Ref Des/Silkscreen Top")
		(7 "B.SilkS" user "Ref Des/Silkscreen Bottom")
		(1 "F.Mask" user "Board Geometry/Soldermask Top")
		(3 "B.Mask" user "Board Geometry/Soldermask Bottom")
		(17 "Dwgs.User" user "User.Drawings")
		(19 "Cmts.User" user "User.Comments")
		(21 "Eco1.User" user "User.Eco1")
		(23 "Eco2.User" user "User.Eco2")
		(25 "Edge.Cuts" user "Board Geometry/Outline")
		(27 "Margin" user)
		(31 "F.CrtYd" user "Package Geometry/Place Bound Top")
		(29 "B.CrtYd" user "Package Geometry/Place Bound Bottom")
		(35 "F.Fab" user "Ref Des/Assembly Top")
		(33 "B.Fab" user "Ref Des/Assembly Bottom")
	)
	(footprint ""
		(layer "F.Cu")
		(at 95.004382 -9.792716 -90)
		(property "Reference" "J1"
			(at -4.160266 3.089402 0)
			(unlocked yes)
			(layer "F.SilkS")
			(effects
				(font
					(size 0.7874 0.5842)
					(thickness 0.1524)
				)
				(justify left)
			)
		)
		(property "Value" ""
			(at 0 0 270)
			(layer "F.Fab")
			(effects
				(font
					(size 1.27 1.27)
				)
			)
		)
		(duplicate_pad_numbers_are_jumpers no)
		(fp_line
			(start -3.150108 8.325104)
			(end -3.150108 6.6421)
			(stroke
				(width 0.1524)
				(type default)
			)
			(layer "F.SilkS")
		)
		(fp_line
			(start 3.150108 8.325104)
			(end -3.150108 8.325104)
			(stroke
				(width 0.1524)
				(type default)
			)
			(layer "F.SilkS")
		)
		(fp_line
			(start 3.150108 6.6421)
			(end 3.150108 8.325104)
			(stroke
				(width 0.1524)
				(type default)
			)
			(layer "F.SilkS")
		)
		(fp_line
			(start -3.150108 5.3467)
			(end -3.150108 4.6355)
			(stroke
				(width 0.1524)
				(type default)
			)
			(layer "F.SilkS")
		)
		(fp_line
			(start 3.150108 4.6482)
			(end 3.150108 5.3594)
			(stroke
				(width 0.1524)
				(type default)
			)
			(layer "F.SilkS")
		)
		(fp_line
			(start -3.150108 3.3401)
			(end -3.150108 2.6416)
			(stroke
				(width 0.1524)
				(type default)
			)
			(layer "F.SilkS")
		)
		(fp_line
			(start 3.150108 2.6416)
			(end 3.150108 3.3528)
			(stroke
				(width 0.1524)
				(type default)
			)
			(layer "F.SilkS")
		)
		(fp_line
			(start -3.150108 1.3589)
			(end -3.150108 0.635)
			(stroke
				(width 0.1524)
				(type default)
			)
			(layer "F.SilkS")
		)
		(fp_line
			(start -2.249932 1.199896)
			(end -3.1496 1.199896)
			(stroke
				(width 0.1524)
				(type default)
			)
			(layer "F.SilkS")
		)
		(fp_line
			(start 3.150108 0.647192)
			(end 3.150108 1.3589)
			(stroke
				(width 0.1524)
				(type default)
			)
			(layer "F.SilkS")
		)
		(fp_line
			(start -2.249932 0.635)
			(end -2.249932 1.199896)
			(stroke
				(width 0.1524)
				(type default)
			)
			(layer "F.SilkS")
		)
		(fp_line
			(start -3.150108 -0.647192)
			(end -3.150108 -1.3589)
			(stroke
				(width 0.1524)
				(type default)
			)
			(layer "F.SilkS")
		)
		(fp_line
			(start -3.1242 -1.199896)
			(end -2.249932 -1.199896)
			(stroke
				(width 0.1524)
				(type default)
			)
			(layer "F.SilkS")
		)
		(fp_line
			(start -2.249932 -1.199896)
			(end -2.249932 -0.635)
			(stroke
				(width 0.1524)
				(type default)
			)
			(layer "F.SilkS")
		)
		(fp_line
			(start 3.150108 -1.3589)
			(end 3.150108 -0.647192)
			(stroke
				(width 0.1524)
				(type default)
			)
			(layer "F.SilkS")
		)
		(fp_line
			(start -3.150108 -2.6416)
			(end -3.150108 -3.3528)
			(stroke
				(width 0.1524)
				(type default)
			)
			(layer "F.SilkS")
		)
		(fp_line
			(start 3.150108 -3.3528)
			(end 3.150108 -2.6416)
			(stroke
				(width 0.1524)
				(type default)
			)
			(layer "F.SilkS")
		)
		(fp_line
			(start -3.150108 -4.65201)
			(end -3.150108 -5.3594)
			(stroke
				(width 0.1524)
				(type default)
			)
			(layer "F.SilkS")
		)
		(fp_line
			(start 3.150108 -5.3594)
			(end 3.150108 -4.65201)
			(stroke
				(width 0.1524)
				(type default)
			)
			(layer "F.SilkS")
		)
		(fp_line
			(start -3.150108 -6.6548)
			(end -3.150108 -8.325104)
			(stroke
				(width 0.1524)
				(type default)
			)
			(layer "F.SilkS")
		)
		(fp_line
			(start -3.150108 -8.325104)
			(end 3.150108 -8.325104)
			(stroke
				(width 0.1524)
				(type default)
			)
			(layer "F.SilkS")
		)
		(fp_line
			(start 3.150108 -8.325104)
			(end 3.150108 -6.6548)
			(stroke
				(width 0.1524)
				(type default)
			)
			(layer "F.SilkS")
		)
		(fp_poly
			(pts
				(xy -1.616964 -10.0965) (xy -2.632964 -10.0965) (xy -2.124964 -8.9535)
			)
			(stroke
				(width 0)
				(type default)
			)
			(fill yes)
			(layer "F.SilkS")
		)
		(fp_poly
			(pts
				(xy -2.249932 0.5588) (xy -2.249932 1.199896) (xy -3.175 1.199896) (xy -3.175 0.5588)
			)
			(stroke
				(width 0)
				(type default)
			)
			(fill yes)
			(layer "F.SilkS")
		)
		(fp_poly
			(pts
				(xy -2.249932 -0.5588) (xy -2.249932 -1.199896) (xy -3.175 -1.199896) (xy -3.175 -0.5588)
			)
			(stroke
				(width 0)
				(type default)
			)
			(fill yes)
			(layer "F.SilkS")
		)
		(fp_poly
			(pts
				(arc
					(start 0.7874 4.99999)
					(mid -0.7874 4.99999)
					(end 0.7874 4.99999)
				)
			)
			(stroke
				(width 0)
				(type default)
			)
			(fill no)
			(layer "B.CrtYd")
		)
		(fp_poly
			(pts
				(arc
					(start 0.7874 -4.99999)
					(mid -0.7874 -4.99999)
					(end 0.7874 -4.99999)
				)
			)
			(stroke
				(width 0)
				(type default)
			)
			(fill no)
			(layer "B.CrtYd")
		)
		(fp_poly
			(pts
				(xy -3.1496 -6.5786) (xy -3.1496 -8.3312) (xy 3.1496 -8.3312) (xy 3.1496 -6.5786) (xy 3.5814 -6.5786)
				(xy 3.5814 6.5786) (xy 3.1496 6.5786) (xy 3.1496 8.3312) (xy -3.1496 8.3312) (xy -3.1496 6.5786)
				(xy -3.5814 6.5786) (xy -3.5814 -6.5786)
			)
			(stroke
				(width 0)
				(type default)
			)
			(fill no)
			(layer "F.CrtYd")
		)
		(fp_line
			(start -3.150108 8.325104)
			(end -3.150108 -8.325104)
			(stroke
				(width 0.1)
				(type default)
			)
			(layer "F.Fab")
		)
		(fp_line
			(start 3.150108 8.325104)
			(end -3.150108 8.325104)
			(stroke
				(width 0.1)
				(type default)
			)
			(layer "F.Fab")
		)
		(fp_line
			(start -3.150108 -8.325104)
			(end 3.150108 -8.325104)
			(stroke
				(width 0.1)
				(type default)
			)
			(layer "F.Fab")
		)
		(fp_line
			(start 3.150108 -8.325104)
			(end 3.150108 8.325104)
			(stroke
				(width 0.1)
				(type default)
			)
			(layer "F.Fab")
		)
		(fp_poly
			(pts
				(xy -1.616964 -10.0965) (xy -2.632964 -10.0965) (xy -2.124964 -8.9535)
			)
			(stroke
				(width 0)
				(type default)
			)
			(fill yes)
			(layer "F.Fab")
		)
		(fp_text user "14"
			(at 4.034028 7.27202 0)
			(unlocked yes)
			(layer "F.SilkS")
			(effects
				(font
					(size 0.635 0.4064)
					(thickness 0.1524)
				)
				(justify left)
			)
		)
		(fp_text user "13"
			(at -4.116832 6.459982 0)
			(unlocked yes)
			(layer "F.SilkS")
			(effects
				(font
					(size 0.635 0.4064)
					(thickness 0.1524)
				)
				(justify left)
			)
		)
		(fp_text user "2"
			(at 3.923284 -6.694932 0)
			(unlocked yes)
			(layer "F.SilkS")
			(effects
				(font
					(size 0.635 0.4064)
					(thickness 0.1524)
				)
				(justify left)
			)
		)
		(fp_text user "1"
			(at -3.820922 -7.16534 0)
			(unlocked yes)
			(layer "F.SilkS")
			(effects
				(font
					(size 0.635 0.4064)
					(thickness 0.1524)
				)
				(justify left)
			)
		)
		(fp_text user "13"
			(at -2.101088 8.509 180)
			(unlocked yes)
			(layer "F.Fab")
			(effects
				(font
					(size 0.7874 0.5842)
					(thickness 0.000001)
				)
				(justify left)
			)
		)
		(fp_text user "14"
			(at 2.013712 8.509 180)
			(unlocked yes)
			(layer "F.Fab")
			(effects
				(font
					(size 0.7874 0.5842)
					(thickness 0.000001)
				)
				(justify left)
			)
		)
		(fp_text user "1"
			(at -2.050288 -8.9535 180)
			(unlocked yes)
			(layer "F.Fab")
			(effects
				(font
					(size 0.7874 0.5842)
					(thickness 0.000001)
				)
				(justify left)
			)
		)
		(fp_text user "2"
			(at 2.085848 -9.0551 180)
			(unlocked yes)
			(layer "F.Fab")
			(effects
				(font
					(size 0.7874 0.5842)
					(thickness 0.000001)
				)
				(justify left)
			)
		)
		(pad "" np_thru_hole circle
			(at 0 -4.99999 180)
			(size 1.0668 1.0668)
			(drill 1.0668)
			(layers "*.Cu" "*.Mask")
			(clearance 0.381)
			(thermal_gap 0.381)
		)
		(pad "" np_thru_hole circle
			(at 0 4.99999 180)
			(size 1.0668 1.0668)
			(drill 1.0668)
			(layers "*.Cu" "*.Mask")
			(clearance 0.381)
			(thermal_gap 0.381)
		)
		(pad "1" smd rect
			(at -2.124964 -5.999988 180)
			(size 1.016 2.7686)
			(layers "F.Cu" "F.Mask" "F.Paste")
			(net "N20512395")
		)
		(pad "2" smd rect
			(at 2.124964 -5.999988 180)
			(size 1.016 2.7686)
			(layers "F.Cu" "F.Mask" "F.Paste")
			(net "TP_P3V3_NODE1_INIT_L")
		)
		(pad "3" smd rect
			(at -2.124964 -3.999992 180)
			(size 1.016 2.7686)
			(layers "F.Cu" "F.Mask" "F.Paste")
			(net "FM_CPLD_NODE1_LPCRST_L")
		)
		(pad "4" smd rect
			(at 2.124964 -3.999992 180)
			(size 1.016 2.7686)
			(layers "F.Cu" "F.Mask" "F.Paste")
			(net "P3V3_NODE1")
		)
		(pad "5" smd rect
			(at -2.124964 -1.999996 180)
			(size 1.016 2.7686)
			(layers "F.Cu" "F.Mask" "F.Paste")
			(net "LPC_CPU_TPM_LAD0")
		)
		(pad "6" smd rect
			(at 2.124964 -1.999996 180)
			(size 1.016 2.7686)
			(layers "F.Cu" "F.Mask" "F.Paste")
			(net "TP_BIOS_NODE1_PORT80_ID0")
		)
		(pad "7" smd rect
			(at -2.124964 0 180)
			(size 1.016 2.7686)
			(layers "F.Cu" "F.Mask" "F.Paste")
			(net "LPC_CPU_TPM_LAD1")
		)
		(pad "8" smd rect
			(at 2.124964 0 180)
			(size 1.016 2.7686)
			(layers "F.Cu" "F.Mask" "F.Paste")
			(net "P5V_NODE1")
		)
		(pad "9" smd rect
			(at -2.124964 1.999996 180)
			(size 1.016 2.7686)
			(layers "F.Cu" "F.Mask" "F.Paste")
			(net "LPC_CPU_TPM_LAD2")
		)
		(pad "10" smd rect
			(at 2.124964 1.999996 180)
			(size 1.016 2.7686)
			(layers "F.Cu" "F.Mask" "F.Paste")
			(net "TPM_LPC_SERIRQ_PORT80_NODE1")
		)
		(pad "11" smd rect
			(at -2.124964 3.999992 180)
			(size 1.016 2.7686)
			(layers "F.Cu" "F.Mask" "F.Paste")
			(net "LPC_CPU_TPM_LAD3")
		)
		(pad "12" smd rect
			(at 2.124964 3.999992 180)
			(size 1.016 2.7686)
			(layers "F.Cu" "F.Mask" "F.Paste")
			(net "GND")
		)
		(pad "13" smd rect
			(at -2.124964 5.999988 180)
			(size 1.016 2.7686)
			(layers "F.Cu" "F.Mask" "F.Paste")
			(net "N20512383")
		)
		(pad "14" smd rect
			(at 2.124964 5.999988 180)
			(size 1.016 2.7686)
			(layers "F.Cu" "F.Mask" "F.Paste")
			(net "GND")
		)
		(zone
			(layers "F.Cu" "B.Cu" "In1.Cu" "In2.Cu" "In3.Cu" "In4.Cu" "In5.Cu" "In6.Cu"
				"In7.Cu" "In8.Cu"
			)
			(hatch none 0.5)
			(connect_pads
				(clearance 0)
			)
			(min_thickness 0.25)
			(keepout
				(tracks not_allowed)
				(vias allowed)
				(pads allowed)
				(copperpour not_allowed)
				(footprints allowed)
			)
			(placement
				(enabled no)
				(sheetname "")
			)
			(fill
				(thermal_gap 0.5)
				(thermal_bridge_width 0.5)
				(island_removal_mode 0)
			)
			(polygon
				(pts
					(arc
						(start 90.944192 -9.792716)
						(mid 90.866697 -9.419012)
						(end 90.647012 -9.106916)
					)
					(xy 90.437716 -9.106916)
					(arc
						(start 90.437716 -8.958834)
						(mid 90.007403 -8.852971)
						(end 89.576402 -8.95604)
					)
					(xy 89.576402 -9.107678)
					(arc
						(start 89.36101 -9.107678)
						(mid 89.064596 -9.793255)
						(end 89.361772 -10.478516)
					)
					(xy 89.57691 -10.478516)
					(arc
						(start 89.57691 -10.629646)
						(mid 90.007687 -10.732494)
						(end 90.437716 -10.626598)
					)
					(xy 90.437716 -10.478516)
					(arc
						(start 90.647012 -10.478516)
						(mid 90.866725 -10.166432)
						(end 90.944192 -9.792716)
					)
				)
			)
		)
		(zone
			(layers "F.Cu" "B.Cu" "In1.Cu" "In2.Cu" "In3.Cu" "In4.Cu" "In5.Cu" "In6.Cu"
				"In7.Cu" "In8.Cu"
			)
			(hatch none 0.5)
			(connect_pads
				(clearance 0)
			)
			(min_thickness 0.25)
			(keepout
				(tracks not_allowed)
				(vias allowed)
				(pads allowed)
				(copperpour not_allowed)
				(footprints allowed)
			)
			(placement
				(enabled no)
				(sheetname "")
			)
			(fill
				(thermal_gap 0.5)
				(thermal_bridge_width 0.5)
				(island_removal_mode 0)
			)
			(polygon
				(pts
					(arc
						(start 100.944172 -9.792716)
						(mid 100.866677 -9.419012)
						(end 100.646992 -9.106916)
					)
					(xy 100.437696 -9.106916)
					(arc
						(start 100.437696 -8.958834)
						(mid 100.007383 -8.852971)
						(end 99.576382 -8.95604)
					)
					(xy 99.576382 -9.107678)
					(arc
						(start 99.36099 -9.107678)
						(mid 99.064576 -9.793255)
						(end 99.361752 -10.478516)
					)
					(xy 99.57689 -10.478516)
					(arc
						(start 99.57689 -10.629646)
						(mid 100.007667 -10.732494)
						(end 100.437696 -10.626598)
					)
					(xy 100.437696 -10.478516)
					(arc
						(start 100.646992 -10.478516)
						(mid 100.866705 -10.166432)
						(end 100.944172 -9.792716)
					)
				)
			)
		)
	)
	(footprint ""
		(layer "F.Cu")
		(at 41.240456 -185.341006 -90)
		(property "Reference" "R1019"
			(at -4.113784 0.130556 90)
			(unlocked yes)
			(layer "F.SilkS")
			(effects
				(font
					(size 0.7874 0.5842)
					(thickness 0.1524)
				)
				(justify left)
			)
		)
		(property "Value" ""
			(at 0 0 270)
			(layer "F.Fab")
			(effects
				(font
					(size 1.27 1.27)
				)
			)
		)
		(duplicate_pad_numbers_are_jumpers no)
		(fp_line
			(start -3.2258 1.3462)
			(end -3.2258 -1.3462)
			(stroke
				(width 0.1524)
				(type default)
			)
			(layer "F.SilkS")
		)
		(fp_line
			(start 3.2258 1.3462)
			(end -3.2258 1.3462)
			(stroke
				(width 0.1524)
				(type default)
			)
			(layer "F.SilkS")
		)
		(fp_line
			(start -3.2258 -1.3462)
			(end 3.2258 -1.3462)
			(stroke
				(width 0.1524)
				(type default)
			)
			(layer "F.SilkS")
		)
		(fp_line
			(start 3.2258 -1.3462)
			(end 3.2258 1.3462)
			(stroke
				(width 0.1524)
				(type default)
			)
			(layer "F.SilkS")
		)
		(fp_poly
			(pts
				(xy -2.5654 1.3462) (xy -2.5654 1.2192) (xy -3.0734 1.2192) (xy -3.0734 -1.2192) (xy -2.5654 -1.2192)
				(xy -2.5654 -1.3462) (xy 2.5654 -1.3462) (xy 2.5654 -1.2192) (xy 3.0734 -1.2192) (xy 3.0734 1.2192)
				(xy 2.5654 1.2192) (xy 2.5654 1.3462)
			)
			(stroke
				(width 0)
				(type default)
			)
			(fill no)
			(layer "F.CrtYd")
		)
		(pad "1" smd rect
			(at -2.350008 0 270)
			(size 1.4224 2.413)
			(layers "F.Cu" "F.Mask" "F.Paste")
			(net "P12V_PDB")
		)
		(pad "2" smd rect
			(at 2.350008 0 270)
			(size 1.4224 2.413)
			(layers "F.Cu" "F.Mask" "F.Paste")
			(net "VSENSE_HSC_NODE1")
		)
	)
	(footprint ""
		(layer "F.Cu")
		(at 17.229074 -36.438078 -90)
		(property "Reference" "R195"
			(at 4.171442 -0.137668 90)
			(unlocked yes)
			(layer "F.SilkS")
			(effects
				(font
					(size 0.7874 0.5842)
					(thickness 0.1524)
				)
				(justify left)
			)
		)
		(property "Value" ""
			(at 0 0 270)
			(layer "F.Fab")
			(effects
				(font
					(size 1.27 1.27)
				)
			)
		)
		(duplicate_pad_numbers_are_jumpers no)
		(fp_line
			(start -0.7874 0.4064)
			(end -0.7874 -0.4064)
			(stroke
				(width 0.1524)
				(type default)
			)
			(layer "F.SilkS")
		)
		(fp_line
			(start 0.7874 0.4064)
			(end -0.7874 0.4064)
			(stroke
				(width 0.1524)
				(type default)
			)
			(layer "F.SilkS")
		)
		(fp_line
			(start -0.7874 -0.4064)
			(end 0.7874 -0.4064)
			(stroke
				(width 0.1524)
				(type default)
			)
			(layer "F.SilkS")
		)
		(fp_line
			(start 0.7874 -0.4064)
			(end 0.7874 0.4064)
			(stroke
				(width 0.1524)
				(type default)
			)
			(layer "F.SilkS")
		)
		(fp_poly
			(pts
				(xy -0.508 0.2794) (xy -0.508 0.2286) (xy -0.635 0.2286) (xy -0.635 -0.254) (xy -0.5334 -0.254)
				(xy -0.5334 -0.2794) (xy 0.5334 -0.2794) (xy 0.5334 -0.254) (xy 0.635 -0.254) (xy 0.635 0.254) (xy 0.5334 0.254)
				(xy 0.5334 0.2794)
			)
			(stroke
				(width 0)
				(type default)
			)
			(fill no)
			(layer "F.CrtYd")
		)
		(pad "1" smd rect
			(at 0.40005 0 270)
			(size 0.4572 0.508)
			(layers "F.Cu" "F.Mask" "F.Paste")
			(net "P3V3_SUS_NODE1")
		)
		(pad "2" smd rect
			(at -0.40005 0 270)
			(size 0.4572 0.508)
			(layers "F.Cu" "F.Mask" "F.Paste")
			(net "CONSOLE_SELECT_N")
		)
	)
	(footprint ""
		(layer "F.Cu")
		(at 122.199908 -8.770112)
		(property "Reference" "H10"
			(at -0.737108 -4.665218 0)
			(unlocked yes)
			(layer "F.SilkS")
			(effects
				(font
					(size 0.7874 0.5842)
					(thickness 0.1524)
				)
				(justify left)
			)
		)
		(property "Value" ""
			(at 0 0 0)
			(layer "F.Fab")
			(effects
				(font
					(size 1.27 1.27)
				)
			)
		)
		(duplicate_pad_numbers_are_jumpers no)
		(fp_poly
			(pts
				(arc
					(start 0 3.9116)
					(mid 0 -3.9116)
					(end 0 3.9116)
				)
			)
			(stroke
				(width 0)
				(type default)
			)
			(fill no)
			(layer "F.CrtYd")
		)
		(pad "1" thru_hole circle
			(at 0 0)
			(size 7.7724 7.7724)
			(drill 5.4102)
			(layers "*.Cu" "*.Mask")
			(remove_unused_layers no)
			(net "GND")
			(clearance -0.9271)
		)
	)
	(footprint ""
		(layer "F.Cu")
		(at 142.910052 -135.18515 180)
		(property "Reference" "R305"
			(at 3.280918 -3.013964 0)
			(unlocked yes)
			(layer "F.SilkS")
			(effects
				(font
					(size 0.7874 0.5842)
					(thickness 0.1524)
				)
				(justify left)
			)
		)
		(property "Value" ""
			(at 0 0 180)
			(layer "F.Fab")
			(effects
				(font
					(size 1.27 1.27)
				)
			)
		)
		(duplicate_pad_numbers_are_jumpers no)
		(fp_line
			(start 0.7874 0.4064)
			(end -0.7874 0.4064)
			(stroke
				(width 0.1524)
				(type default)
			)
			(layer "F.SilkS")
		)
		(fp_line
			(start 0.7874 -0.4064)
			(end 0.7874 0.4064)
			(stroke
				(width 0.1524)
				(type default)
			)
			(layer "F.SilkS")
		)
		(fp_line
			(start -0.7874 0.4064)
			(end -0.7874 -0.4064)
			(stroke
				(width 0.1524)
				(type default)
			)
			(layer "F.SilkS")
		)
		(fp_line
			(start -0.7874 -0.4064)
			(end 0.7874 -0.4064)
			(stroke
				(width 0.1524)
				(type default)
			)
			(layer "F.SilkS")
		)
		(fp_poly
			(pts
				(xy -0.508 0.2794) (xy -0.508 0.2286) (xy -0.635 0.2286) (xy -0.635 -0.254) (xy -0.5334 -0.254)
				(xy -0.5334 -0.2794) (xy 0.5334 -0.2794) (xy 0.5334 -0.254) (xy 0.635 -0.254) (xy 0.635 0.254) (xy 0.5334 0.254)
				(xy 0.5334 0.2794)
			)
			(stroke
				(width 0)
				(type default)
			)
			(fill no)
			(layer "F.CrtYd")
		)
		(pad "1" smd rect
			(at 0.40005 0 180)
			(size 0.4572 0.508)
			(layers "F.Cu" "F.Mask" "F.Paste")
			(net "PCIE_SW_SLOTCLK")
		)
		(pad "2" smd rect
			(at -0.40005 0 180)
			(size 0.4572 0.508)
			(layers "F.Cu" "F.Mask" "F.Paste")
			(net "P3V3_NODE1")
		)
	)
)
